# S9S_MB_2U (Grand Teton) — schematic netlist excerpt (pin names and nets, part order shuffled) for the footprints in the layout excerpt that follows; sources: Cadence DE-HDL packaged netlist, KiCad conversion of 03242023_DA0F0TMBIJ0_F0T_Motherboard_J_brd_V01_OCP.brd

R4267  Q_RES  33.2 1% CHIP  pkg 0402LF  page 222 : A = PWRGD_P3V3_AUX ; B = PWRGD_P3V3_AUX_PDB
R2800  Q_RES  0 5% EMPTY  pkg 0402LF  page 245 : A = SMB_FAN_3V3AUX_R_SCL ; B = SMB_FAN_3V3AUX_BUF_SCL

(kicad_pcb
	(version 20260206)
	(generator "pcbnew")
	(generator_version "10.0")
	(general
		(thickness 1.6)
		(legacy_teardrops no)
	)
	(paper "A4")
	(title_block
		(title "03242023_DA0F0TMBIJ0_F0T_Motherboard_J_brd_V01_OCP.brd")
		(comment 1 "Grand Teton / footprints 4615-4616 of 6105")
	)
	(layers
		(0 "F.Cu" signal "TOP")
		(4 "In1.Cu" signal "GND")
		(6 "In2.Cu" signal "IN1")
		(8 "In3.Cu" signal "GND1")
		(10 "In4.Cu" signal "IN2")
		(12 "In5.Cu" signal "GND2")
		(14 "In6.Cu" signal "IN3")
		(16 "In7.Cu" signal "GND3")
		(18 "In8.Cu" signal "VCC")
		(20 "In9.Cu" signal "VCC1")
		(22 "In10.Cu" signal "GND4")
		(24 "In11.Cu" signal "IN4")
		(26 "In12.Cu" signal "GND5")
		(28 "In13.Cu" signal "IN5")
		(30 "In14.Cu" signal "GND6")
		(32 "In15.Cu" signal "IN6")
		(34 "In16.Cu" signal "GND7")
		(2 "B.Cu" signal "BOTTOM")
		(9 "F.Adhes" user "F.Adhesive")
		(11 "B.Adhes" user "B.Adhesive")
		(13 "F.Paste" user "Package Geometry/Pastemask Top")
		(15 "B.Paste" user "Package Geometry/Pastemask Bottom")
		(5 "F.SilkS" user "Ref Des/Silkscreen Top")
		(7 "B.SilkS" user "Ref Des/Silkscreen Bottom")
		(1 "F.Mask" user "Board Geometry/Soldermask Top")
		(3 "B.Mask" user "Board Geometry/Soldermask Bottom")
		(17 "Dwgs.User" user "User.Drawings")
		(19 "Cmts.User" user "User.Comments")
		(21 "Eco1.User" user "User.Eco1")
		(23 "Eco2.User" user "User.Eco2")
		(25 "Edge.Cuts" user "Board Geometry/Outline")
		(27 "Margin" user)
		(31 "F.CrtYd" user "Package Geometry/Place Bound Top")
		(29 "B.CrtYd" user "Package Geometry/Place Bound Bottom")
		(35 "F.Fab" user "Ref Des/Assembly Top")
		(33 "B.Fab" user "Ref Des/Assembly Bottom")
	)
	(footprint ""
		(layer "B.Cu")
		(at 160.83788 -116.296948)
		(property "Reference" "R4267"
			(at 0 0 0)
			(layer "B.SilkS")
			(hide yes)
			(effects
				(font
					(size 1.27 1.27)
				)
				(justify mirror)
			)
		)
		(property "Value" ""
			(at 0 0 0)
			(layer "B.Fab")
			(effects
				(font
					(size 1.27 1.27)
				)
				(justify mirror)
			)
		)
		(duplicate_pad_numbers_are_jumpers no)
		(fp_line
			(start -0.7874 -0.4064)
			(end -0.7874 0.4064)
			(stroke
				(width 0.1524)
				(type default)
			)
			(layer "B.SilkS")
		)
		(fp_line
			(start -0.7874 0.4064)
			(end 0.7874 0.4064)
			(stroke
				(width 0.1524)
				(type default)
			)
			(layer "B.SilkS")
		)
		(fp_line
			(start 0.7874 -0.4064)
			(end -0.7874 -0.4064)
			(stroke
				(width 0.1524)
				(type default)
			)
			(layer "B.SilkS")
		)
		(fp_line
			(start 0.7874 0.4064)
			(end 0.7874 -0.4064)
			(stroke
				(width 0.1524)
				(type default)
			)
			(layer "B.SilkS")
		)
		(fp_line
			(start -0.67945 -0.3048)
			(end -0.67945 0.3048)
			(stroke
				(width 0.1)
				(type default)
			)
			(layer "B.Fab")
		)
		(fp_line
			(start -0.67945 0.3048)
			(end -0.120396 0.3048)
			(stroke
				(width 0.1)
				(type default)
			)
			(layer "B.Fab")
		)
		(fp_line
			(start -0.12065 -0.3048)
			(end -0.67945 -0.3048)
			(stroke
				(width 0.1)
				(type default)
			)
			(layer "B.Fab")
		)
		(fp_line
			(start -0.12065 -0.2794)
			(end -0.12065 -0.3048)
			(stroke
				(width 0.1)
				(type default)
			)
			(layer "B.Fab")
		)
		(fp_line
			(start -0.120396 0.2794)
			(end 0.12065 0.2794)
			(stroke
				(width 0.1)
				(type default)
			)
			(layer "B.Fab")
		)
		(fp_line
			(start -0.120396 0.3048)
			(end -0.120396 0.2794)
			(stroke
				(width 0.1)
				(type default)
			)
			(layer "B.Fab")
		)
		(fp_line
			(start 0.12065 -0.305054)
			(end 0.12065 -0.2794)
			(stroke
				(width 0.1)
				(type default)
			)
			(layer "B.Fab")
		)
		(fp_line
			(start 0.12065 -0.2794)
			(end -0.12065 -0.2794)
			(stroke
				(width 0.1)
				(type default)
			)
			(layer "B.Fab")
		)
		(fp_line
			(start 0.12065 0.2794)
			(end 0.12065 0.3048)
			(stroke
				(width 0.1)
				(type default)
			)
			(layer "B.Fab")
		)
		(fp_line
			(start 0.12065 0.3048)
			(end 0.67945 0.3048)
			(stroke
				(width 0.1)
				(type default)
			)
			(layer "B.Fab")
		)
		(fp_line
			(start 0.67945 -0.305054)
			(end 0.12065 -0.305054)
			(stroke
				(width 0.1)
				(type default)
			)
			(layer "B.Fab")
		)
		(fp_line
			(start 0.67945 0.3048)
			(end 0.67945 -0.305054)
			(stroke
				(width 0.1)
				(type default)
			)
			(layer "B.Fab")
		)
		(pad "1" smd circle
			(at 0.40005 0 180)
			(size 0 0)
			(layers "B.Cu" "B.Mask" "B.Paste")
			(net "PWRGD_P3V3_AUX")
		)
		(pad "2" smd circle
			(at -0.40005 0 180)
			(size 0 0)
			(layers "B.Cu" "B.Mask" "B.Paste")
			(net "PWRGD_P3V3_AUX_PDB")
		)
	)
	(footprint ""
		(layer "B.Cu")
		(at 180.367686 -423.631614)
		(property "Reference" "R2800"
			(at 0 0 0)
			(layer "B.SilkS")
			(hide yes)
			(effects
				(font
					(size 1.27 1.27)
				)
				(justify mirror)
			)
		)
		(property "Value" ""
			(at 0 0 0)
			(layer "B.Fab")
			(effects
				(font
					(size 1.27 1.27)
				)
				(justify mirror)
			)
		)
		(duplicate_pad_numbers_are_jumpers no)
		(fp_line
			(start -0.7874 -0.4064)
			(end -0.7874 0.4064)
			(stroke
				(width 0.1524)
				(type default)
			)
			(layer "B.SilkS")
		)
		(fp_line
			(start -0.7874 0.4064)
			(end 0.7874 0.4064)
			(stroke
				(width 0.1524)
				(type default)
			)
			(layer "B.SilkS")
		)
		(fp_line
			(start 0.7874 -0.4064)
			(end -0.7874 -0.4064)
			(stroke
				(width 0.1524)
				(type default)
			)
			(layer "B.SilkS")
		)
		(fp_line
			(start 0.7874 0.4064)
			(end 0.7874 -0.4064)
			(stroke
				(width 0.1524)
				(type default)
			)
			(layer "B.SilkS")
		)
		(fp_line
			(start -0.67945 -0.3048)
			(end -0.67945 0.3048)
			(stroke
				(width 0.1)
				(type default)
			)
			(layer "B.Fab")
		)
		(fp_line
			(start -0.67945 0.3048)
			(end -0.120396 0.3048)
			(stroke
				(width 0.1)
				(type default)
			)
			(layer "B.Fab")
		)
		(fp_line
			(start -0.12065 -0.3048)
			(end -0.67945 -0.3048)
			(stroke
				(width 0.1)
				(type default)
			)
			(layer "B.Fab")
		)
		(fp_line
			(start -0.12065 -0.2794)
			(end -0.12065 -0.3048)
			(stroke
				(width 0.1)
				(type default)
			)
			(layer "B.Fab")
		)
		(fp_line
			(start -0.120396 0.2794)
			(end 0.12065 0.2794)
			(stroke
				(width 0.1)
				(type default)
			)
			(layer "B.Fab")
		)
		(fp_line
			(start -0.120396 0.3048)
			(end -0.120396 0.2794)
			(stroke
				(width 0.1)
				(type default)
			)
			(layer "B.Fab")
		)
		(fp_line
			(start 0.12065 -0.305054)
			(end 0.12065 -0.2794)
			(stroke
				(width 0.1)
				(type default)
			)
			(layer "B.Fab")
		)
		(fp_line
			(start 0.12065 -0.2794)
			(end -0.12065 -0.2794)
			(stroke
				(width 0.1)
				(type default)
			)
			(layer "B.Fab")
		)
		(fp_line
			(start 0.12065 0.2794)
			(end 0.12065 0.3048)
			(stroke
				(width 0.1)
				(type default)
			)
			(layer "B.Fab")
		)
		(fp_line
			(start 0.12065 0.3048)
			(end 0.67945 0.3048)
			(stroke
				(width 0.1)
				(type default)
			)
			(layer "B.Fab")
		)
		(fp_line
			(start 0.67945 -0.305054)
			(end 0.12065 -0.305054)
			(stroke
				(width 0.1)
				(type default)
			)
			(layer "B.Fab")
		)
		(fp_line
			(start 0.67945 0.3048)
			(end 0.67945 -0.305054)
			(stroke
				(width 0.1)
				(type default)
			)
			(layer "B.Fab")
		)
		(pad "1" smd circle
			(at 0.40005 0 180)
			(size 0 0)
			(layers "B.Cu" "B.Mask" "B.Paste")
			(net "SMB_FAN_3V3AUX_R_SCL")
		)
		(pad "2" smd circle
			(at -0.40005 0 180)
			(size 0 0)
			(layers "B.Cu" "B.Mask" "B.Paste")
			(net "SMB_FAN_3V3AUX_BUF_SCL")
		)
	)
)
